FILE_TYPE = CONNECTIVITY;
{Allegro Design Entry HDL 17.2-2016 S081 (4005846) 1/11/2022}
"PAGE_NUMBER" = 104;
0"NC";
1"P3V3_AUX\g";
2"P12V_S3_AUX_CPU1_NVDIMM\g";
3"P12V_S3_AUX_CPU1_NVDIMM\g";
4"P3V3_AUX\g";
5"GND\g";
6"GND\g";
7"GND\g";
8"GND\g";
9"GND\g";
10"M_D_CPU1_SA_DQ<31:0>";
11"M_D_CPU1_SA_CB<7:0>";
12"M_D_CPU1_SB_CB<7:0>";
13"M_D_CPU1_SA_CA<6:0>";
14"M_D_CPU1_SB_CA<6:0>";
15"M_D_CPU1_SB_DQ<31:0>";
16"M_D_CPU1_SB_DQS_DP<9:0>";
17"M_D_CPU1_SA_DQS_DP<9:0>";
18"M_D_CPU1_SB_DQS_DN<9:0>";
19"M_D_CPU1_SA_DQS_DN<9:0>";
20"PD_CHD_CPU1_DIMM1_SAA";
21"TP_CHD_CPU1_DIMM1_FRU_0";
22"M_D_CPU1_SB_DQ<20>";
23"M_D_CPU1_ALERT_N";
24"I3C_SPD_DDRABCD_CPU1_LVC1_SDA";
25"PD_CHD_CPU1_DIMM1_SAA";
26"I3C_SPD_DDRABCD_CPU1_LVC1_SCL_R7";
27"RST_M_CD_CPU1_FPGA_N";
28"I3C_SPD_DDRABCD_CPU1_LVC1_SCL";
29"PWRGD_CHD_CPU1_DIMM1";
30"TP_CHD_CPU1_DIMM1_FRU_6";
31"M_D_CPU1_SB_DQS_DN<4>";
32"M_D_CPU1_SA_DQS_DN<8>";
33"M_D_CPU1_SA_DQS_DN<9>";
34"M_D_CPU1_SA_DQS_DN<7>";
35"M_D_CPU1_SA_DQS_DN<6>";
36"M_D_CPU1_SA_DQS_DN<5>";
37"M_D_CPU1_SA_DQS_DN<3>";
38"M_D_CPU1_SA_DQS_DN<4>";
39"M_D_CPU1_SA_DQS_DN<2>";
40"M_D_CPU1_SA_DQS_DN<1>";
41"M_D_CPU1_SA_DQS_DN<0>";
42"M_D_CPU1_SB_DQS_DN<9>";
43"M_D_CPU1_SB_DQS_DN<8>";
44"M_D_CPU1_SB_DQS_DN<7>";
45"M_D_CPU1_SB_DQS_DN<6>";
46"M_D_CPU1_SB_DQS_DN<5>";
47"M_D_CPU1_SB_DQS_DN<3>";
48"M_D_CPU1_SB_DQS_DN<2>";
49"M_D_CPU1_SB_DQS_DN<1>";
50"M_D_CPU1_SB_DQS_DN<0>";
51"M_D_CPU1_SA_DQS_DP<9>";
52"M_D_CPU1_SA_DQS_DP<8>";
53"M_D_CPU1_SA_DQS_DP<7>";
54"M_D_CPU1_SA_DQS_DP<6>";
55"M_D_CPU1_SA_DQS_DP<5>";
56"M_D_CPU1_SA_DQS_DP<4>";
57"M_D_CPU1_SA_DQS_DP<3>";
58"M_D_CPU1_SA_DQS_DP<2>";
59"M_D_CPU1_SA_DQS_DP<1>";
60"M_D_CPU1_SA_DQS_DP<0>";
61"M_D_CPU1_SB_DQS_DP<9>";
62"M_D_CPU1_SB_DQS_DP<8>";
63"M_D_CPU1_SB_DQS_DP<7>";
64"M_D_CPU1_SB_DQS_DP<6>";
65"M_D_CPU1_SB_DQS_DP<5>";
66"M_D_CPU1_SB_DQS_DP<4>";
67"M_D_CPU1_SB_DQS_DP<3>";
68"M_D_CPU1_SB_DQS_DP<2>";
69"M_D_CPU1_SB_DQS_DP<0>";
70"M_D_CPU1_SB_DQS_DP<1>";
71"M_D_CPU1_SA_DQ<1>";
72"M_D_CPU1_SB_DQ<16>";
73"M_D_CPU1_SB_CB<1>";
74"TP_CHD_CPU1_DIMM1_FRU_1";
75"TP_CHD_CPU1_DIMM1_FRU_2";
76"TP_CHD_CPU1_DIMM1_FRU_3";
77"TP_CHD_CPU1_DIMM1_FRU_4";
78"TP_CHD_CPU1_DIMM1_FRU_5";
79"M_D_CPU1_SB_PAR";
80"M_D_CPU1_SA_PAR";
81"M_D_CPU1_SB_RSP<0>";
82"M_D_CPU1_SA_RSP<0>";
83"M_D_CPU1_SB_DQ<0>";
84"M_D_CPU1_SB_DQ<1>";
85"M_D_CPU1_SB_DQ<2>";
86"M_D_CPU1_SB_DQ<3>";
87"M_D_CPU1_SB_DQ<4>";
88"M_D_CPU1_SB_DQ<5>";
89"M_D_CPU1_SB_DQ<6>";
90"M_D_CPU1_SB_DQ<7>";
91"M_D_CPU1_SB_DQ<8>";
92"M_D_CPU1_SB_DQ<9>";
93"M_D_CPU1_SB_DQ<10>";
94"M_D_CPU1_SB_DQ<11>";
95"M_D_CPU1_SB_DQ<12>";
96"M_D_CPU1_SB_DQ<13>";
97"M_D_CPU1_SB_DQ<14>";
98"M_D_CPU1_SB_DQ<15>";
99"M_D_CPU1_SB_DQ<17>";
100"M_D_CPU1_SB_DQ<18>";
101"M_D_CPU1_SB_DQ<19>";
102"M_D_CPU1_SB_DQ<21>";
103"M_D_CPU1_SB_DQ<22>";
104"M_D_CPU1_SB_DQ<23>";
105"M_D_CPU1_SB_DQ<24>";
106"M_D_CPU1_SB_DQ<25>";
107"M_D_CPU1_SB_DQ<26>";
108"M_D_CPU1_SB_DQ<27>";
109"M_D_CPU1_SB_DQ<28>";
110"M_D_CPU1_SB_DQ<29>";
111"M_D_CPU1_SB_DQ<30>";
112"M_D_CPU1_SB_DQ<31>";
113"M_D_CPU1_SA_DQ<0>";
114"M_D_CPU1_SA_DQ<2>";
115"M_D_CPU1_SA_DQ<3>";
116"M_D_CPU1_SA_DQ<4>";
117"M_D_CPU1_SA_DQ<5>";
118"M_D_CPU1_SA_DQ<6>";
119"M_D_CPU1_SA_DQ<7>";
120"M_D_CPU1_SA_DQ<8>";
121"M_D_CPU1_SA_DQ<9>";
122"M_D_CPU1_SA_DQ<10>";
123"M_D_CPU1_SA_DQ<11>";
124"M_D_CPU1_SA_DQ<12>";
125"M_D_CPU1_SA_DQ<13>";
126"M_D_CPU1_SA_DQ<14>";
127"M_D_CPU1_SA_DQ<15>";
128"M_D_CPU1_SA_DQ<16>";
129"M_D_CPU1_SA_DQ<17>";
130"M_D_CPU1_SA_DQ<18>";
131"M_D_CPU1_SA_DQ<19>";
132"M_D_CPU1_SA_DQ<20>";
133"M_D_CPU1_SA_DQ<21>";
134"M_D_CPU1_SA_DQ<22>";
135"M_D_CPU1_SA_DQ<23>";
136"M_D_CPU1_SA_DQ<24>";
137"M_D_CPU1_SA_DQ<25>";
138"M_D_CPU1_SA_DQ<26>";
139"M_D_CPU1_SA_DQ<27>";
140"M_D_CPU1_SA_DQ<28>";
141"M_D_CPU1_SA_DQ<29>";
142"M_D_CPU1_SA_DQ<30>";
143"M_D_CPU1_SB_CS_N<1>";
144"M_D_CPU1_SA_CS_N<1>";
145"M_D_CPU1_SB_CS_N<0>";
146"M_D_CPU1_SA_CS_N<0>";
147"M_D_CPU1_CLK_DP<0>";
148"M_D_CPU1_CLK_DN<0>";
149"M_D_CPU1_SB_CB<0>";
150"M_D_CPU1_SB_CB<2>";
151"M_D_CPU1_SB_CB<3>";
152"M_D_CPU1_SB_CB<4>";
153"M_D_CPU1_SB_CB<5>";
154"M_D_CPU1_SB_CB<6>";
155"M_D_CPU1_SA_CB<0>";
156"M_D_CPU1_SA_CB<2>";
157"M_D_CPU1_SA_CB<3>";
158"M_D_CPU1_SA_CB<5>";
159"M_D_CPU1_SA_CB<6>";
160"M_D_CPU1_SB_CA<6>";
161"M_D_CPU1_SA_CA<6>";
162"M_D_CPU1_SB_CA<5>";
163"M_D_CPU1_SA_CA<5>";
164"M_D_CPU1_SB_CA<4>";
165"M_D_CPU1_SA_CA<4>";
166"M_D_CPU1_SB_CA<3>";
167"M_D_CPU1_SA_CA<3>";
168"M_D_CPU1_SB_CA<2>";
169"M_D_CPU1_SA_CA<2>";
170"M_D_CPU1_SB_CA<1>";
171"M_D_CPU1_SA_CA<1>";
172"M_D_CPU1_SB_CA<0>";
173"M_D_CPU1_SA_CA<0>";
174"M_D_CPU1_SB_CB<7>";
175"M_D_CPU1_SA_CB<1>";
176"M_D_CPU1_SA_CB<4>";
177"M_D_CPU1_SA_CB<7>";
178"M_D_CPU1_SA_DQ<31>";
%"UNIVERSAL_GND"
"1","(-3100,-250)","0","logical_power","I1";
;
HDL_POWER"GND"
CDS_LIB"logical_power";
"A"5;
%"TAP"
"1","(-1675,3375)","0","standard","I100";
;
CDS_LIB"standard"
BODY_TYPE"PLUMBING"
HDL_TAP"TRUE";
"B \NAC \NWC"10;
"S \NAC"
BN"16"128;
%"TAP"
"1","(-1675,3325)","0","standard","I101";
;
CDS_LIB"standard"
BODY_TYPE"PLUMBING"
HDL_TAP"TRUE";
"B \NAC \NWC"10;
"S \NAC"
BN"15"127;
%"TAP"
"1","(-1675,3225)","0","standard","I102";
;
CDS_LIB"standard"
BODY_TYPE"PLUMBING"
HDL_TAP"TRUE";
"B \NAC \NWC"10;
"S \NAC"
BN"13"125;
%"TAP"
"1","(-1675,3275)","0","standard","I103";
;
CDS_LIB"standard"
BODY_TYPE"PLUMBING"
HDL_TAP"TRUE";
"B \NAC \NWC"10;
"S \NAC"
BN"14"126;
%"TAP"
"1","(-1675,3175)","0","standard","I104";
;
CDS_LIB"standard"
BODY_TYPE"PLUMBING"
HDL_TAP"TRUE";
"B \NAC \NWC"10;
"S \NAC"
BN"12"124;
%"TAP"
"1","(-1675,3425)","0","standard","I105";
;
CDS_LIB"standard"
BODY_TYPE"PLUMBING"
HDL_TAP"TRUE";
"B \NAC \NWC"10;
"S \NAC"
BN"17"129;
%"TAP"
"1","(-1675,3525)","0","standard","I106";
;
CDS_LIB"standard"
BODY_TYPE"PLUMBING"
HDL_TAP"TRUE";
"B \NAC \NWC"10;
"S \NAC"
BN"19"131;
%"TAP"
"1","(-1675,3475)","0","standard","I107";
;
CDS_LIB"standard"
BODY_TYPE"PLUMBING"
HDL_TAP"TRUE";
"B \NAC \NWC"10;
"S \NAC"
BN"18"130;
%"TAP"
"1","(-1675,3575)","0","standard","I108";
;
CDS_LIB"standard"
BODY_TYPE"PLUMBING"
HDL_TAP"TRUE";
"B \NAC \NWC"10;
"S \NAC"
BN"20"132;
%"TAP"
"1","(-1675,3625)","0","standard","I109";
;
CDS_LIB"standard"
BODY_TYPE"PLUMBING"
HDL_TAP"TRUE";
"B \NAC \NWC"10;
"S \NAC"
BN"21"133;
%"TAP"
"1","(-1675,3675)","0","standard","I110";
;
CDS_LIB"standard"
BODY_TYPE"PLUMBING"
HDL_TAP"TRUE";
"B \NAC \NWC"10;
"S \NAC"
BN"22"134;
%"TAP"
"1","(-1675,3725)","0","standard","I111";
;
CDS_LIB"standard"
BODY_TYPE"PLUMBING"
HDL_TAP"TRUE";
"B \NAC \NWC"10;
"S \NAC"
BN"23"135;
%"TAP"
"1","(-1675,3775)","0","standard","I112";
;
CDS_LIB"standard"
BODY_TYPE"PLUMBING"
HDL_TAP"TRUE";
"B \NAC \NWC"10;
"S \NAC"
BN"24"136;
%"TAP"
"1","(-1675,3875)","0","standard","I113";
;
CDS_LIB"standard"
BODY_TYPE"PLUMBING"
HDL_TAP"TRUE";
"B \NAC \NWC"10;
"S \NAC"
BN"26"138;
%"TAP"
"1","(-1675,3825)","0","standard","I114";
;
CDS_LIB"standard"
BODY_TYPE"PLUMBING"
HDL_TAP"TRUE";
"B \NAC \NWC"10;
"S \NAC"
BN"25"137;
%"TAP"
"1","(-1675,3925)","0","standard","I115";
;
CDS_LIB"standard"
BODY_TYPE"PLUMBING"
HDL_TAP"TRUE";
"B \NAC \NWC"10;
"S \NAC"
BN"27"139;
%"TAP"
"1","(-1675,4025)","0","standard","I116";
;
CDS_LIB"standard"
BODY_TYPE"PLUMBING"
HDL_TAP"TRUE";
"B \NAC \NWC"10;
"S \NAC"
BN"29"141;
%"TAP"
"1","(-1675,3975)","0","standard","I117";
;
CDS_LIB"standard"
BODY_TYPE"PLUMBING"
HDL_TAP"TRUE";
"B \NAC \NWC"10;
"S \NAC"
BN"28"140;
%"TAP"
"1","(-1675,4125)","0","standard","I118";
;
CDS_LIB"standard"
BODY_TYPE"PLUMBING"
HDL_TAP"TRUE";
"B \NAC \NWC"10;
"S \NAC"
BN"31"178;
%"TAP"
"1","(-1675,4075)","0","standard","I119";
;
CDS_LIB"standard"
BODY_TYPE"PLUMBING"
HDL_TAP"TRUE";
"B \NAC \NWC"10;
"S \NAC"
BN"30"142;
%"VCC_CORE"
"1","(-4150,2000)","0","logical_power","I12";
;
HDL_POWER"P3V3_AUX"
CDS_LIB"logical_power";
"A"4;
%"UNIVERSAL_GND"
"1","(50,-125)","0","logical_power","I120";
;
HDL_POWER"GND"
CDS_LIB"logical_power";
"A"6;
%"UNIVERSAL_GND"
"1","(1675,-125)","0","logical_power","I121";
;
HDL_POWER"GND"
CDS_LIB"logical_power";
"A"7;
%"Q_CAP"
"1","(50,250)","0","pure_quanta","I122";
;
PART_NUMBER"CH5221MEB00"
VOLTAGE"6.3V"
VALUE"2.2UF"
MATERIAL"X6S"
TOLERANCE"20%"
PACK_TYPE"C0402"
$LOCATION"C68"
CDS_LIB"pure_quanta"
$LOCATION"C68"
CDS_LOCATION"C68"
$SEC"1"
CDS_SEC"1";
"B"
$PN"2"6;
"A"
$PN"1"1;
%"VCC_CORE"
"1","(50,575)","0","logical_power","I123";
;
HDL_POWER"P3V3_AUX"
CDS_LIB"logical_power";
"A"1;
%"Q_CAP"
"1","(1050,250)","0","pure_quanta","I127";
;
PART_NUMBER"CH6103KEA00"
VALUE"10UF"
PACK_TYPE"C0805"
VOLTAGE"16V"
TOLERANCE"10%"
MATERIAL"X6S"
$LOCATION"C69"
CDS_LIB"pure_quanta"
$LOCATION"C69"
CDS_LOCATION"C69"
$SEC"1"
CDS_SEC"1";
"B"
$PN"2"7;
"A"
$PN"1"2;
%"VCC_CORE"
"1","(1050,575)","0","logical_power","I128";
;
HDL_POWER"P12V_S3_AUX_CPU1_NVDIMM"
CDS_LIB"logical_power";
"A"2;
%"Q_CAP"
"1","(1675,250)","0","pure_quanta","I129";
;
PART_NUMBER"CH6103KEA00"
PACK_TYPE"C0805"
VOLTAGE"16V"
TOLERANCE"10%"
VALUE"10UF"
MATERIAL"X6S"
$LOCATION"C70"
CDS_LIB"pure_quanta"
$LOCATION"C70"
CDS_LOCATION"C70"
$SEC"1"
CDS_SEC"1";
"B"
$PN"2"7;
"A"
$PN"1"2;
%"TAP"
"1","(1075,2275)","0","standard","I130";
;
CDS_LIB"standard"
BODY_TYPE"PLUMBING"
HDL_TAP"TRUE";
"B \NAC \NWC"16;
"S \NAC"
BN"1"70;
%"TAP"
"1","(1075,2175)","0","standard","I131";
;
CDS_LIB"standard"
BODY_TYPE"PLUMBING"
HDL_TAP"TRUE";
"B \NAC \NWC"16;
"S \NAC"
BN"0"69;
%"TAP"
"1","(1075,2375)","0","standard","I132";
;
CDS_LIB"standard"
BODY_TYPE"PLUMBING"
HDL_TAP"TRUE";
"B \NAC \NWC"16;
"S \NAC"
BN"2"68;
%"TAP"
"1","(1075,2575)","0","standard","I133";
;
CDS_LIB"standard"
BODY_TYPE"PLUMBING"
HDL_TAP"TRUE";
"B \NAC \NWC"16;
"S \NAC"
BN"4"66;
%"TAP"
"1","(1075,2475)","0","standard","I134";
;
CDS_LIB"standard"
BODY_TYPE"PLUMBING"
HDL_TAP"TRUE";
"B \NAC \NWC"16;
"S \NAC"
BN"3"67;
%"TAP"
"1","(1075,2775)","0","standard","I135";
;
CDS_LIB"standard"
BODY_TYPE"PLUMBING"
HDL_TAP"TRUE";
"B \NAC \NWC"16;
"S \NAC"
BN"6"64;
%"TAP"
"1","(1075,2675)","0","standard","I136";
;
CDS_LIB"standard"
BODY_TYPE"PLUMBING"
HDL_TAP"TRUE";
"B \NAC \NWC"16;
"S \NAC"
BN"5"65;
%"TAP"
"1","(1075,2875)","0","standard","I137";
;
CDS_LIB"standard"
BODY_TYPE"PLUMBING"
HDL_TAP"TRUE";
"B \NAC \NWC"16;
"S \NAC"
BN"7"63;
%"TAP"
"1","(1075,3075)","0","standard","I138";
;
CDS_LIB"standard"
BODY_TYPE"PLUMBING"
HDL_TAP"TRUE";
"B \NAC \NWC"16;
"S \NAC"
BN"9"61;
%"TAP"
"1","(1075,2975)","0","standard","I139";
;
CDS_LIB"standard"
BODY_TYPE"PLUMBING"
HDL_TAP"TRUE";
"B \NAC \NWC"16;
"S \NAC"
BN"8"62;
%"TAP"
"1","(1250,2125)","0","standard","I140";
;
CDS_LIB"standard"
BODY_TYPE"PLUMBING"
HDL_TAP"TRUE";
"B \NAC \NWC"18;
"S \NAC"
BN"0"50;
%"TAP"
"1","(1250,2225)","0","standard","I141";
;
CDS_LIB"standard"
BODY_TYPE"PLUMBING"
HDL_TAP"TRUE";
"B \NAC \NWC"18;
"S \NAC"
BN"1"49;
%"TAP"
"1","(1250,2325)","0","standard","I142";
;
CDS_LIB"standard"
BODY_TYPE"PLUMBING"
HDL_TAP"TRUE";
"B \NAC \NWC"18;
"S \NAC"
BN"2"48;
%"TAP"
"1","(1250,2425)","0","standard","I143";
;
CDS_LIB"standard"
BODY_TYPE"PLUMBING"
HDL_TAP"TRUE";
"B \NAC \NWC"18;
"S \NAC"
BN"3"47;
%"TAP"
"1","(1250,2525)","0","standard","I144";
;
CDS_LIB"standard"
BODY_TYPE"PLUMBING"
HDL_TAP"TRUE";
"B \NAC \NWC"18;
"S \NAC"
BN"4"31;
%"TAP"
"1","(1250,2625)","0","standard","I145";
;
CDS_LIB"standard"
BODY_TYPE"PLUMBING"
HDL_TAP"TRUE";
"B \NAC \NWC"18;
"S \NAC"
BN"5"46;
%"TAP"
"1","(1250,2725)","0","standard","I146";
;
CDS_LIB"standard"
BODY_TYPE"PLUMBING"
HDL_TAP"TRUE";
"B \NAC \NWC"18;
"S \NAC"
BN"6"45;
%"TAP"
"1","(1250,2825)","0","standard","I147";
;
CDS_LIB"standard"
BODY_TYPE"PLUMBING"
HDL_TAP"TRUE";
"B \NAC \NWC"18;
"S \NAC"
BN"7"44;
%"TAP"
"1","(1250,2925)","0","standard","I148";
;
CDS_LIB"standard"
BODY_TYPE"PLUMBING"
HDL_TAP"TRUE";
"B \NAC \NWC"18;
"S \NAC"
BN"8"43;
%"TAP"
"1","(1250,3025)","0","standard","I149";
;
CDS_LIB"standard"
BODY_TYPE"PLUMBING"
HDL_TAP"TRUE";
"B \NAC \NWC"18;
"S \NAC"
BN"9"42;
%"TAP"
"1","(1075,3225)","0","standard","I150";
;
CDS_LIB"standard"
BODY_TYPE"PLUMBING"
HDL_TAP"TRUE";
"B \NAC \NWC"17;
"S \NAC"
BN"0"60;
%"TAP"
"1","(1075,3325)","0","standard","I151";
;
CDS_LIB"standard"
BODY_TYPE"PLUMBING"
HDL_TAP"TRUE";
"B \NAC \NWC"17;
"S \NAC"
BN"1"59;
%"TAP"
"1","(1075,3425)","0","standard","I152";
;
CDS_LIB"standard"
BODY_TYPE"PLUMBING"
HDL_TAP"TRUE";
"B \NAC \NWC"17;
"S \NAC"
BN"2"58;
%"TAP"
"1","(1075,3625)","0","standard","I153";
;
CDS_LIB"standard"
BODY_TYPE"PLUMBING"
HDL_TAP"TRUE";
"B \NAC \NWC"17;
"S \NAC"
BN"4"56;
%"TAP"
"1","(1075,3525)","0","standard","I154";
;
CDS_LIB"standard"
BODY_TYPE"PLUMBING"
HDL_TAP"TRUE";
"B \NAC \NWC"17;
"S \NAC"
BN"3"57;
%"TAP"
"1","(1075,3725)","0","standard","I155";
;
CDS_LIB"standard"
BODY_TYPE"PLUMBING"
HDL_TAP"TRUE";
"B \NAC \NWC"17;
"S \NAC"
BN"5"55;
%"TAP"
"1","(1075,3825)","0","standard","I156";
;
CDS_LIB"standard"
BODY_TYPE"PLUMBING"
HDL_TAP"TRUE";
"B \NAC \NWC"17;
"S \NAC"
BN"6"54;
%"TAP"
"1","(1075,3925)","0","standard","I157";
;
CDS_LIB"standard"
BODY_TYPE"PLUMBING"
HDL_TAP"TRUE";
"B \NAC \NWC"17;
"S \NAC"
BN"7"53;
%"TAP"
"1","(1075,4125)","0","standard","I158";
;
CDS_LIB"standard"
BODY_TYPE"PLUMBING"
HDL_TAP"TRUE";
"B \NAC \NWC"17;
"S \NAC"
BN"9"51;
%"TAP"
"1","(1075,4025)","0","standard","I159";
;
CDS_LIB"standard"
BODY_TYPE"PLUMBING"
HDL_TAP"TRUE";
"B \NAC \NWC"17;
"S \NAC"
BN"8"52;
%"TAP"
"1","(1250,3175)","0","standard","I160";
;
CDS_LIB"standard"
BODY_TYPE"PLUMBING"
HDL_TAP"TRUE";
"B \NAC \NWC"19;
"S \NAC"
BN"0"41;
%"TAP"
"1","(1250,3275)","0","standard","I161";
;
CDS_LIB"standard"
BODY_TYPE"PLUMBING"
HDL_TAP"TRUE";
"B \NAC \NWC"19;
"S \NAC"
BN"1"40;
%"TAP"
"1","(1250,3375)","0","standard","I162";
;
CDS_LIB"standard"
BODY_TYPE"PLUMBING"
HDL_TAP"TRUE";
"B \NAC \NWC"19;
"S \NAC"
BN"2"39;
%"TAP"
"1","(1250,3475)","0","standard","I163";
;
CDS_LIB"standard"
BODY_TYPE"PLUMBING"
HDL_TAP"TRUE";
"B \NAC \NWC"19;
"S \NAC"
BN"3"37;
%"TAP"
"1","(1250,3575)","0","standard","I164";
;
CDS_LIB"standard"
BODY_TYPE"PLUMBING"
HDL_TAP"TRUE";
"B \NAC \NWC"19;
"S \NAC"
BN"4"38;
%"TAP"
"1","(1250,3675)","0","standard","I165";
;
CDS_LIB"standard"
BODY_TYPE"PLUMBING"
HDL_TAP"TRUE";
"B \NAC \NWC"19;
"S \NAC"
BN"5"36;
%"TAP"
"1","(1250,3775)","0","standard","I166";
;
CDS_LIB"standard"
BODY_TYPE"PLUMBING"
HDL_TAP"TRUE";
"B \NAC \NWC"19;
"S \NAC"
BN"6"35;
%"TAP"
"1","(1250,3875)","0","standard","I167";
;
CDS_LIB"standard"
BODY_TYPE"PLUMBING"
HDL_TAP"TRUE";
"B \NAC \NWC"19;
"S \NAC"
BN"7"34;
%"TAP"
"1","(1250,3975)","0","standard","I168";
;
CDS_LIB"standard"
BODY_TYPE"PLUMBING"
HDL_TAP"TRUE";
"B \NAC \NWC"19;
"S \NAC"
BN"8"32;
%"TAP"
"1","(1250,4075)","0","standard","I169";
;
CDS_LIB"standard"
BODY_TYPE"PLUMBING"
HDL_TAP"TRUE";
"B \NAC \NWC"19;
"S \NAC"
BN"9"33;
%"UNIVERSAL_GND"
"1","(2750,425)","0","logical_power","I174";
;
HDL_POWER"GND"
CDS_LIB"logical_power";
"A"8;
%"SCONN288_ADR50017P130CC"
"3","(3600,2500)","0","pure_quanta","I175";
;
PART_NUMBER"DFHST8FS461"
MATERIAL"IO"
PART_TYPE"SMLF"
VALUE"SCONN288_ADR50017-P130CC"
$LOCATION"J23"
NEEDS_NO_SIZE"TRUE"
CDS_LMAN_SYM_OUTLINE"-450,1775,450,-1775"
CDS_LIB"pure_quanta"
CDS_LOCATION"J23"
$SEC"3"
CDS_SEC"3";
"G3"
$PN"G3"9;
"G2"
$PN"G2"9;
"G1"
$PN"G1"9;
"VSS62"
$PN"141"9;
"VSS61"
$PN"139"9;
"VSS60"
$PN"136"9;
"VSS58"
$PN"132"9;
"VSS104"
$PN"240"8;
"VSS102"
$PN"235"8;
"VSS100"
$PN"230"8;
"VIN_BULK2"
$PN"146"3;
"VIN_BULK1"
$PN"145"3;
"VIN_BULK0"
$PN"1"3;
"VSS126"
$PN"288"8;
"VSS125"
$PN"286"8;
"VSS124"
$PN"284"8;
"VSS123"
$PN"281"8;
"VSS122"
$PN"279"8;
"VSS121"
$PN"277"8;
"VSS120"
$PN"275"8;
"VSS119"
$PN"273"8;
"VSS118"
$PN"270"8;
"VSS117"
$PN"268"8;
"VSS116"
$PN"266"8;
"VSS115"
$PN"264"8;
"VSS114"
$PN"262"8;
"VSS113"
$PN"259"8;
"VSS112"
$PN"257"8;
"VSS111"
$PN"255"8;
"VSS110"
$PN"253"8;
"VSS109"
$PN"251"8;
"VSS108"
$PN"248"8;
"VSS107"
$PN"246"8;
"VSS106"
$PN"244"8;
"VSS105"
$PN"242"8;
"VSS103"
$PN"237"8;
"VSS101"
$PN"233"8;
"VSS99"
$PN"228"8;
"VSS98"
$PN"226"8;
"VSS97"
$PN"224"8;
"VSS96"
$PN"222"8;
"VSS95"
$PN"219"8;
"VSS94"
$PN"216"8;
"VSS93"
$PN"214"8;
"VSS92"
$PN"212"8;
"VSS91"
$PN"210"8;
"VSS90"
$PN"208"8;
"VSS89"
$PN"206"8;
"VSS88"
$PN"204"8;
"VSS87"
$PN"202"8;
"VSS86"
$PN"199"8;
"VSS85"
$PN"197"8;
"VSS84"
$PN"195"8;
"VSS83"
$PN"193"8;
"VSS82"
$PN"191"8;
"VSS81"
$PN"188"8;
"VSS80"
$PN"186"8;
"VSS79"
$PN"184"8;
"VSS78"
$PN"182"8;
"VSS77"
$PN"180"8;
"VSS76"
$PN"177"8;
"VSS75"
$PN"175"8;
"VSS74"
$PN"173"8;
"VSS73"
$PN"171"8;
"VSS72"
$PN"169"8;
"VSS71"
$PN"166"8;
"VSS70"
$PN"164"8;
"VSS69"
$PN"162"8;
"VSS68"
$PN"160"8;
"VSS67"
$PN"158"8;
"VSS66"
$PN"155"8;
"VSS65"
$PN"153"8;
"VSS64"
$PN"151"8;
"VSS63"
$PN"143"9;
"VSS59"
$PN"134"9;
"VSS57"
$PN"130"9;
"VSS56"
$PN"128"9;
"VSS55"
$PN"125"9;
"VSS54"
$PN"123"9;
"VSS53"
$PN"121"9;
"VSS52"
$PN"119"9;
"VSS51"
$PN"117"9;
"VSS50"
$PN"114"9;
"VSS49"
$PN"112"9;
"VSS48"
$PN"110"9;
"VSS47"
$PN"108"9;
"VSS46"
$PN"106"9;
"VSS45"
$PN"103"9;
"VSS44"
$PN"101"9;
"VSS43"
$PN"99"9;
"VSS42"
$PN"97"9;
"VSS41"
$PN"95"9;
"VSS40"
$PN"92"9;
"VSS39"
$PN"90"9;
"VSS38"
$PN"88"9;
"VSS37"
$PN"85"9;
"VSS36"
$PN"83"9;
"VSS35"
$PN"81"9;
"VSS34"
$PN"79"9;
"VSS33"
$PN"77"9;
"VSS32"
$PN"75"9;
"VSS31"
$PN"73"9;
"VSS30"
$PN"71"9;
"VSS29"
$PN"69"9;
"VSS28"
$PN"67"9;
"VSS27"
$PN"65"9;
"VSS26"
$PN"63"9;
"VSS25"
$PN"61"9;
"VSS24"
$PN"59"9;
"VSS23"
$PN"57"9;
"VSS22"
$PN"54"9;
"VSS21"
$PN"52"9;
"VSS20"
$PN"50"9;
"VSS19"
$PN"48"9;
"VSS18"
$PN"46"9;
"VSS17"
$PN"43"9;
"VSS16"
$PN"41"9;
"VSS15"
$PN"39"9;
"VSS14"
$PN"37"9;
"VSS13"
$PN"35"9;
"VSS12"
$PN"32"9;
"VSS11"
$PN"30"9;
"VSS10"
$PN"28"9;
"VSS9"
$PN"26"9;
"VSS8"
$PN"24"9;
"VSS7"
$PN"21"9;
"VSS6"
$PN"19"9;
"VSS5"
$PN"17"9;
"VSS4"
$PN"15"9;
"VSS3"
$PN"13"9;
"VSS2"
$PN"10"9;
"VSS1"
$PN"8"9;
"VSS0"
$PN"6"9;
%"UNIVERSAL_GND"
"1","(4450,425)","0","logical_power","I176";
;
HDL_POWER"GND"
CDS_LIB"logical_power";
"A"9;
%"VCC_CORE"
"1","(2750,4675)","0","logical_power","I177";
;
HDL_POWER"P12V_S3_AUX_CPU1_NVDIMM"
CDS_LIB"logical_power";
"A"3;
%"SCONN288_ADR50017P130CC"
"2","(175,3125)","0","pure_quanta","I178";
;
PART_NUMBER"DFHST8FS461"
MATERIAL"IO"
PART_TYPE"SMLF"
VALUE"SCONN288_ADR50017-P130CC"
LOCATION"J23"
NEEDS_NO_SIZE"TRUE"
CDS_LMAN_SYM_OUTLINE"-600,1150,600,-1150"
CDS_LIB"pure_quanta"
$SEC"2"
CDS_SEC"2";
"DQS7_A_C||TDQS7_A_C \B"
$PN"178"34;
"DQS6_A_T||TDQS6_A_T"
$PN"168"54;
"DQS8_B_T||TDQS8_B_T"
$PN"283"62;
"DQS8_B_C||TDQS8_B_C \B"
$PN"282"43;
"DQS7_B_T||TDQS7_B_T"
$PN"272"63;
"DQS0_A_C \B"
$PN"12"41;
"DQS0_A_T"
$PN"11"60;
"DQS0_B_C \B"
$PN"105"50;
"DQS0_B_T"
$PN"104"69;
"DQS1_A_C \B"
$PN"23"40;
"DQS1_A_T"
$PN"22"59;
"DQS1_B_C \B"
$PN"116"49;
"DQS1_B_T"
$PN"115"70;
"DQS2_A_C \B"
$PN"34"39;
"DQS2_A_T"
$PN"33"58;
"DQS2_B_C \B"
$PN"127"48;
"DQS2_B_T"
$PN"126"68;
"DQS3_A_C \B"
$PN"45"37;
"DQS3_A_T"
$PN"44"57;
"DQS3_B_C \B"
$PN"138"47;
"DQS3_B_T"
$PN"137"67;
"DQS4_A_C \B"
$PN"56"38;
"DQS4_A_T"
$PN"55"56;
"DQS4_B_C \B"
$PN"238"31;
"DQS4_B_T"
$PN"239"66;
"DQS5_A_C||TDQS5_A_C||DQS5_A_T||TDQS5_A_T \B"
$PN"156"36;
"DQS5_A_T||TDQS5_A_T"
$PN"157"55;
"DQS5_B_C||TDQS5_B_C \B"
$PN"249"46;
"DQS5_B_T||TDQS5_B_T"
$PN"250"65;
"DQS6_A_C||TDQS6_A_C||DQS6_A_T||TDQS6_A_T \B"
$PN"167"35;
"DQS6_B_C||TDQS6_B_C \B"
$PN"260"45;
"DQS6_B_T||TDQS6_B_T"
$PN"261"64;
"DQS7_A_T||TDQS7_A_T"
$PN"179"53;
"DQS7_B_C||TDQS7_B_C \B"
$PN"271"44;
"DQS8_A_C||TDQS8_A_C \B"
$PN"189"32;
"DQS8_A_T||TDQS8_A_T"
$PN"190"52;
"DQS9_A_C||TDQS9_A_C \B"
$PN"200"33;
"DQS9_A_T||TDQS9_A_T"
$PN"201"51;
"DQS9_B_C||TDQS9_B_C \B"
$PN"94"42;
"DQS9_B_T||TDQS9_B_T||DBI4_B_N"
$PN"93"61;
%"Q_RES"
"1","(-4300,1425)","0","pure_quanta","I180";
;
PART_NUMBER"CS04992FB07"
VALUE"49.9"
MATERIAL"CHIP"
$LOCATION"R3897"
CDS_LIB"pure_quanta"
PACK_TYPE"0402LF"
TOLERANCE"1%"
WATTAGE"1/16W"
CDS_LOCATION"R3897"
$SEC"1"
CDS_SEC"1";
"B"
$PN"2"28;
"A"
$PN"1"26;
%"Q_RES"
"2","(-3100,-25)","0","pure_quanta","I2";
;
PART_NUMBER"CS41272FB07"
VALUE"127K"
TOLERANCE"1%"
WATTAGE"1/16W"
PACK_TYPE"0402LF"
MATERIAL"CHIP"
$LOCATION"R48"
CDS_LIB"pure_quanta"
$LOCATION"R48"
CDS_LOCATION"R48"
$SEC"1"
CDS_SEC"1";
"A"
$PN"1"20;
"B"
$PN"2"5;
%"SCONN288_ADR50017P130CC"
"1","(-2500,2400)","0","pure_quanta","I25";
;
PART_NUMBER"DFHST8FS461"
MATERIAL"IO"
VALUE"SCONN288_ADR50017-P130CC"
PART_TYPE"SMLF"
$LOCATION"J23"
NEEDS_NO_SIZE"TRUE"
CDS_LMAN_SYM_OUTLINE"-450,1875,450,-1875"
CDS_LIB"pure_quanta"
CDS_LOCATION"J23"
$SEC"1"
CDS_SEC"1";
"DQ31_A"
$PN"194"178;
"CB7_A"
$PN"205"177;
"CB4_A"
$PN"58"176;
"CB1_A"
$PN"53"175;
"CB7_B"
$PN"236"174;
"ALERT_N \B"
$PN"62"23;
"CA0_A"
$PN"66"173;
"CA0_B"
$PN"76"172;
"CA1_A"
$PN"211"171;
"CA1_B"
$PN"221"170;
"CA2_A"
$PN"68"169;
"CA2_B"
$PN"78"168;
"CA3_A"
$PN"213"167;
"CA3_B"
$PN"223"166;
"CA4_A"
$PN"70"165;
"CA4_B"
$PN"80"164;
"CA5_A"
$PN"215"163;
"CA5_B"
$PN"225"162;
"CA6_A"
$PN"72"161;
"CA6_B"
$PN"82"160;
"CB6_A"
$PN"203"159;
"CB5_A"
$PN"60"158;
"CB3_A"
$PN"198"157;
"CB2_A"
$PN"196"156;
"CB0_A"
$PN"51"155;
"CB6_B"
$PN"234"154;
"CB5_B"
$PN"91"153;
"CB4_B"
$PN"89"152;
"CB3_B"
$PN"243"151;
"CB2_B"
$PN"241"150;
"CB1_B"
$PN"98"73;
"CB0_B"
$PN"96"149;
"CK_C \B"
$PN"218"148;
"CK_T"
$PN"217"147;
"CS0_A_N"
$PN"64"146;
"CS0_B_N"
$PN"84"145;
"CS1_A_N"
$PN"209"144;
"CS1_B_N"
$PN"229"143;
"DQ30_A"
$PN"192"142;
"DQ29_A"
$PN"49"141;
"DQ28_A"
$PN"47"140;
"DQ27_A"
$PN"187"139;
"DQ26_A"
$PN"185"138;
"DQ25_A"
$PN"42"137;
"DQ24_A"
$PN"40"136;
"DQ23_A"
$PN"183"135;
"DQ22_A"
$PN"181"134;
"DQ21_A"
$PN"38"133;
"DQ20_A"
$PN"36"132;
"DQ19_A"
$PN"176"131;
"DQ18_A"
$PN"174"130;
"DQ17_A"
$PN"31"129;
"DQ16_A"
$PN"29"128;
"DQ15_A"
$PN"172"127;
"DQ14_A"
$PN"170"126;
"DQ13_A"
$PN"27"125;
"DQ12_A"
$PN"25"124;
"DQ11_A"
$PN"165"123;
"DQ10_A"
$PN"163"122;
"DQ9_A"
$PN"20"121;
"DQ8_A"
$PN"18"120;
"DQ7_A"
$PN"161"119;
"DQ6_A"
$PN"159"118;
"DQ5_A"
$PN"16"117;
"DQ4_A"
$PN"14"116;
"DQ3_A"
$PN"154"115;
"DQ2_A"
$PN"152"114;
"DQ1_A"
$PN"9"71;
"DQ0_A"
$PN"7"113;
"DQ31_B"
$PN"287"112;
"DQ30_B"
$PN"285"111;
"DQ29_B"
$PN"142"110;
"DQ28_B"
$PN"140"109;
"DQ27_B"
$PN"280"108;
"DQ26_B"
$PN"278"107;
"DQ25_B"
$PN"135"106;
"DQ24_B"
$PN"133"105;
"DQ23_B"
$PN"276"104;
"DQ22_B"
$PN"274"103;
"DQ21_B"
$PN"131"102;
"DQ20_B"
$PN"129"22;
"DQ19_B"
$PN"269"101;
"DQ18_B"
$PN"267"100;
"DQ17_B"
$PN"124"99;
"DQ16_B"
$PN"122"72;
"DQ15_B"
$PN"265"98;
"DQ14_B"
$PN"263"97;
"DQ13_B"
$PN"120"96;
"DQ12_B"
$PN"118"95;
"DQ11_B"
$PN"258"94;
"DQ10_B"
$PN"256"93;
"DQ9_B"
$PN"113"92;
"DQ8_B"
$PN"111"91;
"DQ7_B"
$PN"254"90;
"DQ6_B"
$PN"252"89;
"DQ5_B"
$PN"109"88;
"DQ4_B"
$PN"107"87;
"DQ3_B"
$PN"247"86;
"DQ2_B"
$PN"245"85;
"DQ1_B"
$PN"102"84;
"DQ0_B"
$PN"100"83;
"HSA"
$PN"148"25;
"HSCL"
$PN"4"26;
"HSDA"
$PN"5"24;
"LBD||RSP_A_N"
$PN"86"82;
"LBS||RSP_B_N"
$PN"87"81;
"PAR_A"
$PN"74"80;
"PAR_B"
$PN"227"79;
"PWR_GOOD||FAIL_N"
$PN"147"29;
"RESET_N \B"
$PN"207"27;
"RFU6"
$PN"232"30;
"RFU5"
$PN"231"78;
"RFU4"
$PN"220"77;
"RFU3"
$PN"150"76;
"RFU2"
$PN"149"75;
"RFU1"
$PN"144"74;
"RFU0"
$PN"2"21;
"VIN_MGMT"
$PN"3"4;
%"TAP"
"1","(-3325,2025)","2","standard","I26";
;
CDS_LIB"standard"
BODY_TYPE"PLUMBING"
HDL_TAP"TRUE";
"B \NAC \NWC"12;
"S \NAC"
BN"2"150;
%"TAP"
"1","(-3325,2075)","2","standard","I27";
;
CDS_LIB"standard"
BODY_TYPE"PLUMBING"
HDL_TAP"TRUE";
"B \NAC \NWC"12;
"S \NAC"
BN"3"151;
%"TAP"
"1","(-3325,1975)","2","standard","I28";
;
CDS_LIB"standard"
BODY_TYPE"PLUMBING"
HDL_TAP"TRUE";
"B \NAC \NWC"12;
"S \NAC"
BN"1"73;
%"TAP"
"1","(-3325,1925)","2","standard","I29";
;
CDS_LIB"standard"
BODY_TYPE"PLUMBING"
HDL_TAP"TRUE";
"B \NAC \NWC"12;
"S \NAC"
BN"0"149;
%"TAP"
"1","(-1675,1025)","0","standard","I30";
;
CDS_LIB"standard"
BODY_TYPE"PLUMBING"
HDL_TAP"TRUE";
"B \NAC \NWC"15;
"S \NAC"
BN"2"85;
%"TAP"
"1","(-1675,1075)","0","standard","I31";
;
CDS_LIB"standard"
BODY_TYPE"PLUMBING"
HDL_TAP"TRUE";
"B \NAC \NWC"15;
"S \NAC"
BN"3"86;
%"TAP"
"1","(-1675,925)","0","standard","I32";
;
CDS_LIB"standard"
BODY_TYPE"PLUMBING"
HDL_TAP"TRUE";
"B \NAC \NWC"15;
"S \NAC"
BN"0"83;
%"TAP"
"1","(-1675,975)","0","standard","I33";
;
CDS_LIB"standard"
BODY_TYPE"PLUMBING"
HDL_TAP"TRUE";
"B \NAC \NWC"15;
"S \NAC"
BN"1"84;
%"TAP"
"1","(-1675,1225)","0","standard","I34";
;
CDS_LIB"standard"
BODY_TYPE"PLUMBING"
HDL_TAP"TRUE";
"B \NAC \NWC"15;
"S \NAC"
BN"6"89;
%"TAP"
"1","(-1675,1175)","0","standard","I35";
;
CDS_LIB"standard"
BODY_TYPE"PLUMBING"
HDL_TAP"TRUE";
"B \NAC \NWC"15;
"S \NAC"
BN"5"88;
%"TAP"
"1","(-1675,1125)","0","standard","I36";
;
CDS_LIB"standard"
BODY_TYPE"PLUMBING"
HDL_TAP"TRUE";
"B \NAC \NWC"15;
"S \NAC"
BN"4"87;
%"TAP"
"1","(-1675,1275)","0","standard","I37";
;
CDS_LIB"standard"
BODY_TYPE"PLUMBING"
HDL_TAP"TRUE";
"B \NAC \NWC"15;
"S \NAC"
BN"7"90;
%"TAP"
"1","(-1675,1325)","0","standard","I38";
;
CDS_LIB"standard"
BODY_TYPE"PLUMBING"
HDL_TAP"TRUE";
"B \NAC \NWC"15;
"S \NAC"
BN"8"91;
%"TAP"
"1","(-1675,1575)","0","standard","I39";
;
CDS_LIB"standard"
BODY_TYPE"PLUMBING"
HDL_TAP"TRUE";
"B \NAC \NWC"15;
"S \NAC"
BN"13"96;
%"TAP"
"1","(-1675,1525)","0","standard","I40";
;
CDS_LIB"standard"
BODY_TYPE"PLUMBING"
HDL_TAP"TRUE";
"B \NAC \NWC"15;
"S \NAC"
BN"12"95;
%"TAP"
"1","(-1675,1425)","0","standard","I41";
;
CDS_LIB"standard"
BODY_TYPE"PLUMBING"
HDL_TAP"TRUE";
"B \NAC \NWC"15;
"S \NAC"
BN"10"93;
%"TAP"
"1","(-1675,1475)","0","standard","I42";
;
CDS_LIB"standard"
BODY_TYPE"PLUMBING"
HDL_TAP"TRUE";
"B \NAC \NWC"15;
"S \NAC"
BN"11"94;
%"TAP"
"1","(-1675,1375)","0","standard","I43";
;
CDS_LIB"standard"
BODY_TYPE"PLUMBING"
HDL_TAP"TRUE";
"B \NAC \NWC"15;
"S \NAC"
BN"9"92;
%"TAP"
"1","(-1675,1625)","0","standard","I44";
;
CDS_LIB"standard"
BODY_TYPE"PLUMBING"
HDL_TAP"TRUE";
"B \NAC \NWC"15;
"S \NAC"
BN"14"97;
%"TAP"
"1","(-1675,1675)","0","standard","I45";
;
CDS_LIB"standard"
BODY_TYPE"PLUMBING"
HDL_TAP"TRUE";
"B \NAC \NWC"15;
"S \NAC"
BN"15"98;
%"TAP"
"1","(-1675,1725)","0","standard","I46";
;
CDS_LIB"standard"
BODY_TYPE"PLUMBING"
HDL_TAP"TRUE";
"B \NAC \NWC"15;
"S \NAC"
BN"16"72;
%"TAP"
"1","(-1675,1825)","0","standard","I47";
;
CDS_LIB"standard"
BODY_TYPE"PLUMBING"
HDL_TAP"TRUE";
"B \NAC \NWC"15;
"S \NAC"
BN"18"100;
%"TAP"
"1","(-1675,1775)","0","standard","I48";
;
CDS_LIB"standard"
BODY_TYPE"PLUMBING"
HDL_TAP"TRUE";
"B \NAC \NWC"15;
"S \NAC"
BN"17"99;
%"TAP"
"1","(-1675,2075)","0","standard","I49";
;
CDS_LIB"standard"
BODY_TYPE"PLUMBING"
HDL_TAP"TRUE";
"B \NAC \NWC"15;
"S \NAC"
BN"23"104;
%"TAP"
"1","(-1675,2025)","0","standard","I50";
;
CDS_LIB"standard"
BODY_TYPE"PLUMBING"
HDL_TAP"TRUE";
"B \NAC \NWC"15;
"S \NAC"
BN"22"103;
%"TAP"
"1","(-1675,1925)","0","standard","I51";
;
CDS_LIB"standard"
BODY_TYPE"PLUMBING"
HDL_TAP"TRUE";
"B \NAC \NWC"15;
"S \NAC"
BN"20"22;
%"TAP"
"1","(-1675,1975)","0","standard","I52";
;
CDS_LIB"standard"
BODY_TYPE"PLUMBING"
HDL_TAP"TRUE";
"B \NAC \NWC"15;
"S \NAC"
BN"21"102;
%"TAP"
"1","(-1675,1875)","0","standard","I53";
;
CDS_LIB"standard"
BODY_TYPE"PLUMBING"
HDL_TAP"TRUE";
"B \NAC \NWC"15;
"S \NAC"
BN"19"101;
%"TAP"
"1","(-3325,2225)","2","standard","I54";
;
CDS_LIB"standard"
BODY_TYPE"PLUMBING"
HDL_TAP"TRUE";
"B \NAC \NWC"12;
"S \NAC"
BN"6"154;
%"TAP"
"1","(-3325,2275)","2","standard","I55";
;
CDS_LIB"standard"
BODY_TYPE"PLUMBING"
HDL_TAP"TRUE";
"B \NAC \NWC"12;
"S \NAC"
BN"7"174;
%"TAP"
"1","(-3325,2175)","2","standard","I56";
;
CDS_LIB"standard"
BODY_TYPE"PLUMBING"
HDL_TAP"TRUE";
"B \NAC \NWC"12;
"S \NAC"
BN"5"153;
%"TAP"
"1","(-3325,2125)","2","standard","I57";
;
CDS_LIB"standard"
BODY_TYPE"PLUMBING"
HDL_TAP"TRUE";
"B \NAC \NWC"12;
"S \NAC"
BN"4"152;
%"TAP"
"1","(-3325,2375)","2","standard","I58";
;
CDS_LIB"standard"
BODY_TYPE"PLUMBING"
HDL_TAP"TRUE";
"B \NAC \NWC"11;
"S \NAC"
BN"0"155;
%"TAP"
"1","(-3325,2475)","2","standard","I59";
;
CDS_LIB"standard"
BODY_TYPE"PLUMBING"
HDL_TAP"TRUE";
"B \NAC \NWC"11;
"S \NAC"
BN"2"156;
%"TAP"
"1","(-3325,2425)","2","standard","I60";
;
CDS_LIB"standard"
BODY_TYPE"PLUMBING"
HDL_TAP"TRUE";
"B \NAC \NWC"11;
"S \NAC"
BN"1"175;
%"TAP"
"1","(-3325,2575)","2","standard","I61";
;
CDS_LIB"standard"
BODY_TYPE"PLUMBING"
HDL_TAP"TRUE";
"B \NAC \NWC"11;
"S \NAC"
BN"4"176;
%"TAP"
"1","(-3325,2525)","2","standard","I62";
;
CDS_LIB"standard"
BODY_TYPE"PLUMBING"
HDL_TAP"TRUE";
"B \NAC \NWC"11;
"S \NAC"
BN"3"157;
%"TAP"
"1","(-3325,2625)","2","standard","I63";
;
CDS_LIB"standard"
BODY_TYPE"PLUMBING"
HDL_TAP"TRUE";
"B \NAC \NWC"11;
"S \NAC"
BN"5"158;
%"TAP"
"1","(-3325,2675)","2","standard","I64";
;
CDS_LIB"standard"
BODY_TYPE"PLUMBING"
HDL_TAP"TRUE";
"B \NAC \NWC"11;
"S \NAC"
BN"6"159;
%"TAP"
"1","(-3325,2725)","2","standard","I65";
;
CDS_LIB"standard"
BODY_TYPE"PLUMBING"
HDL_TAP"TRUE";
"B \NAC \NWC"11;
"S \NAC"
BN"7"177;
%"TAP"
"1","(-3325,3425)","2","standard","I66";
;
CDS_LIB"standard"
BODY_TYPE"PLUMBING"
HDL_TAP"TRUE";
"B \NAC \NWC"14;
"S \NAC"
BN"0"172;
%"TAP"
"1","(-3325,3475)","2","standard","I67";
;
CDS_LIB"standard"
BODY_TYPE"PLUMBING"
HDL_TAP"TRUE";
"B \NAC \NWC"14;
"S \NAC"
BN"1"170;
%"TAP"
"1","(-3325,3525)","2","standard","I68";
;
CDS_LIB"standard"
BODY_TYPE"PLUMBING"
HDL_TAP"TRUE";
"B \NAC \NWC"14;
"S \NAC"
BN"2"168;
%"TAP"
"1","(-3325,3575)","2","standard","I69";
;
CDS_LIB"standard"
BODY_TYPE"PLUMBING"
HDL_TAP"TRUE";
"B \NAC \NWC"14;
"S \NAC"
BN"3"166;
%"TAP"
"1","(-3325,3625)","2","standard","I70";
;
CDS_LIB"standard"
BODY_TYPE"PLUMBING"
HDL_TAP"TRUE";
"B \NAC \NWC"14;
"S \NAC"
BN"4"164;
%"TAP"
"1","(-3325,3725)","2","standard","I71";
;
CDS_LIB"standard"
BODY_TYPE"PLUMBING"
HDL_TAP"TRUE";
"B \NAC \NWC"14;
"S \NAC"
BN"6"160;
%"TAP"
"1","(-3325,3875)","2","standard","I72";
;
CDS_LIB"standard"
BODY_TYPE"PLUMBING"
HDL_TAP"TRUE";
"B \NAC \NWC"13;
"S \NAC"
BN"1"171;
%"TAP"
"1","(-3325,3825)","2","standard","I73";
;
CDS_LIB"standard"
BODY_TYPE"PLUMBING"
HDL_TAP"TRUE";
"B \NAC \NWC"13;
"S \NAC"
BN"0"173;
%"TAP"
"1","(-3325,3675)","2","standard","I74";
;
CDS_LIB"standard"
BODY_TYPE"PLUMBING"
HDL_TAP"TRUE";
"B \NAC \NWC"14;
"S \NAC"
BN"5"162;
%"TAP"
"1","(-3325,3925)","2","standard","I75";
;
CDS_LIB"standard"
BODY_TYPE"PLUMBING"
HDL_TAP"TRUE";
"B \NAC \NWC"13;
"S \NAC"
BN"2"169;
%"TAP"
"1","(-3325,3975)","2","standard","I76";
;
CDS_LIB"standard"
BODY_TYPE"PLUMBING"
HDL_TAP"TRUE";
"B \NAC \NWC"13;
"S \NAC"
BN"3"167;
%"TAP"
"1","(-3325,4125)","2","standard","I77";
;
CDS_LIB"standard"
BODY_TYPE"PLUMBING"
HDL_TAP"TRUE";
"B \NAC \NWC"13;
"S \NAC"
BN"6"161;
%"TAP"
"1","(-3325,4075)","2","standard","I78";
;
CDS_LIB"standard"
BODY_TYPE"PLUMBING"
HDL_TAP"TRUE";
"B \NAC \NWC"13;
"S \NAC"
BN"5"163;
%"TAP"
"1","(-3325,4025)","2","standard","I79";
;
CDS_LIB"standard"
BODY_TYPE"PLUMBING"
HDL_TAP"TRUE";
"B \NAC \NWC"13;
"S \NAC"
BN"4"165;
%"TAP"
"1","(-1675,2225)","0","standard","I80";
;
CDS_LIB"standard"
BODY_TYPE"PLUMBING"
HDL_TAP"TRUE";
"B \NAC \NWC"15;
"S \NAC"
BN"26"107;
%"TAP"
"1","(-1675,2175)","0","standard","I81";
;
CDS_LIB"standard"
BODY_TYPE"PLUMBING"
HDL_TAP"TRUE";
"B \NAC \NWC"15;
"S \NAC"
BN"25"106;
%"TAP"
"1","(-1675,2125)","0","standard","I82";
;
CDS_LIB"standard"
BODY_TYPE"PLUMBING"
HDL_TAP"TRUE";
"B \NAC \NWC"15;
"S \NAC"
BN"24"105;
%"TAP"
"1","(-1675,2325)","0","standard","I83";
;
CDS_LIB"standard"
BODY_TYPE"PLUMBING"
HDL_TAP"TRUE";
"B \NAC \NWC"15;
"S \NAC"
BN"28"109;
%"TAP"
"1","(-1675,2375)","0","standard","I84";
;
CDS_LIB"standard"
BODY_TYPE"PLUMBING"
HDL_TAP"TRUE";
"B \NAC \NWC"15;
"S \NAC"
BN"29"110;
%"TAP"
"1","(-1675,2275)","0","standard","I85";
;
CDS_LIB"standard"
BODY_TYPE"PLUMBING"
HDL_TAP"TRUE";
"B \NAC \NWC"15;
"S \NAC"
BN"27"108;
%"TAP"
"1","(-1675,2625)","0","standard","I86";
;
CDS_LIB"standard"
BODY_TYPE"PLUMBING"
HDL_TAP"TRUE";
"B \NAC \NWC"10;
"S \NAC"
BN"1"71;
%"TAP"
"1","(-1675,2575)","0","standard","I87";
;
CDS_LIB"standard"
BODY_TYPE"PLUMBING"
HDL_TAP"TRUE";
"B \NAC \NWC"10;
"S \NAC"
BN"0"113;
%"TAP"
"1","(-1675,2425)","0","standard","I88";
;
CDS_LIB"standard"
BODY_TYPE"PLUMBING"
HDL_TAP"TRUE";
"B \NAC \NWC"15;
"S \NAC"
BN"30"111;
%"TAP"
"1","(-1675,2475)","0","standard","I89";
;
CDS_LIB"standard"
BODY_TYPE"PLUMBING"
HDL_TAP"TRUE";
"B \NAC \NWC"15;
"S \NAC"
BN"31"112;
%"TAP"
"1","(-1675,2725)","0","standard","I90";
;
CDS_LIB"standard"
BODY_TYPE"PLUMBING"
HDL_TAP"TRUE";
"B \NAC \NWC"10;
"S \NAC"
BN"3"115;
%"TAP"
"1","(-1675,2675)","0","standard","I91";
;
CDS_LIB"standard"
BODY_TYPE"PLUMBING"
HDL_TAP"TRUE";
"B \NAC \NWC"10;
"S \NAC"
BN"2"114;
%"TAP"
"1","(-1675,2825)","0","standard","I92";
;
CDS_LIB"standard"
BODY_TYPE"PLUMBING"
HDL_TAP"TRUE";
"B \NAC \NWC"10;
"S \NAC"
BN"5"117;
%"TAP"
"1","(-1675,2875)","0","standard","I93";
;
CDS_LIB"standard"
BODY_TYPE"PLUMBING"
HDL_TAP"TRUE";
"B \NAC \NWC"10;
"S \NAC"
BN"6"118;
%"TAP"
"1","(-1675,2775)","0","standard","I94";
;
CDS_LIB"standard"
BODY_TYPE"PLUMBING"
HDL_TAP"TRUE";
"B \NAC \NWC"10;
"S \NAC"
BN"4"116;
%"TAP"
"1","(-1675,2925)","0","standard","I95";
;
CDS_LIB"standard"
BODY_TYPE"PLUMBING"
HDL_TAP"TRUE";
"B \NAC \NWC"10;
"S \NAC"
BN"7"119;
%"TAP"
"1","(-1675,2975)","0","standard","I96";
;
CDS_LIB"standard"
BODY_TYPE"PLUMBING"
HDL_TAP"TRUE";
"B \NAC \NWC"10;
"S \NAC"
BN"8"120;
%"TAP"
"1","(-1675,3025)","0","standard","I97";
;
CDS_LIB"standard"
BODY_TYPE"PLUMBING"
HDL_TAP"TRUE";
"B \NAC \NWC"10;
"S \NAC"
BN"9"121;
%"TAP"
"1","(-1675,3075)","0","standard","I98";
;
CDS_LIB"standard"
BODY_TYPE"PLUMBING"
HDL_TAP"TRUE";
"B \NAC \NWC"10;
"S \NAC"
BN"10"122;
%"TAP"
"1","(-1675,3125)","0","standard","I99";
;
CDS_LIB"standard"
BODY_TYPE"PLUMBING"
HDL_TAP"TRUE";
"B \NAC \NWC"10;
"S \NAC"
BN"11"123;
END.
